(kicad_pcb
	(version 20260206)
	(generator "pcbnew")
	(generator_version "10.0")
	(general
		(thickness 1.6)
		(legacy_teardrops no)
	)
	(paper "A4")
	(title_block
		(title "fcb — 12433-1M.1206WZS1330.brd")
		(comment 1 "Open Vault / Knox (Wiwynn) / footprints 262-268 of 495")
	)
	(layers
		(0 "F.Cu" signal "TOP")
		(4 "In1.Cu" signal "L2GND")
		(6 "In2.Cu" signal "L3VCC")
		(2 "B.Cu" signal "BOTTOM")
		(9 "F.Adhes" user "F.Adhesive")
		(11 "B.Adhes" user "B.Adhesive")
		(13 "F.Paste" user "Package Geometry/Pastemask Top")
		(15 "B.Paste" user "Package Geometry/Pastemask Bottom")
		(5 "F.SilkS" user "Ref Des/Silkscreen Top")
		(7 "B.SilkS" user "Ref Des/Silkscreen Bottom")
		(1 "F.Mask" user "Board Geometry/Soldermask Top")
		(3 "B.Mask" user "Board Geometry/Soldermask Bottom")
		(17 "Dwgs.User" user "User.Drawings")
		(19 "Cmts.User" user "User.Comments")
		(21 "Eco1.User" user "User.Eco1")
		(23 "Eco2.User" user "User.Eco2")
		(25 "Edge.Cuts" user "Board Geometry/Outline")
		(27 "Margin" user)
		(31 "F.CrtYd" user "Package Geometry/Place Bound Top")
		(29 "B.CrtYd" user "Package Geometry/Place Bound Bottom")
		(35 "F.Fab" user "Ref Des/Assembly Top")
		(33 "B.Fab" user "Ref Des/Assembly Bottom")
	)
	(footprint ""
		(layer "F.Cu")
		(at 29.972 -361.315 180)
		(property "Reference" "PR15"
			(at 0 0 180)
			(layer "F.SilkS")
			(hide yes)
			(effects
				(font
					(size 1.27 1.27)
				)
			)
		)
		(property "Value" "4K7R2J-2-GP"
			(at 0.064008 -3.993896 180)
			(unlocked yes)
			(layer "F.Fab")
			(hide yes)
			(effects
				(font
					(size 1.016 1.016)
					(thickness 0.1524)
				)
			)
		)
		(property "Device Type" "R402H16"
			(at 0.064008 -5.517896 180)
			(unlocked yes)
			(layer "F.Fab")
			(hide yes)
			(effects
				(font
					(size 1.016 1.016)
					(thickness 0.1524)
				)
			)
		)
		(duplicate_pad_numbers_are_jumpers no)
		(fp_line
			(start 0.508 -0.9398)
			(end -0.508 -0.9398)
			(stroke
				(width 0.1524)
				(type default)
			)
			(layer "F.SilkS")
		)
		(fp_line
			(start -0.508 -0.9398)
			(end -0.508 0.9398)
			(stroke
				(width 0.1524)
				(type default)
			)
			(layer "F.SilkS")
		)
		(fp_rect
			(start -0.508 0.9398)
			(end 0.508 -0.9398)
			(stroke
				(width 0)
				(type default)
			)
			(fill no)
			(layer "F.CrtYd")
		)
		(fp_rect
			(start -0.508 0.9398)
			(end 0.508 -0.9398)
			(stroke
				(width 0)
				(type default)
			)
			(fill no)
			(layer "F.Fab")
		)
		(pad "1" smd custom
			(at 0 -0.4445 180)
			(size 0.1397 0.1397)
			(layers "F.Cu" "F.Mask" "F.Paste")
			(net "P3V3")
			(options
				(clearance outline)
				(anchor circle)
			)
			(primitives
				(gr_poly
					(pts
						(arc
							(start -0.1778 -0.2794)
							(mid -0.249642 -0.249642)
							(end -0.2794 -0.1778)
						)
						(arc
							(start -0.2794 0.1778)
							(mid -0.249642 0.249642)
							(end -0.1778 0.2794)
						)
						(arc
							(start 0.1778 0.2794)
							(mid 0.249642 0.249642)
							(end 0.2794 0.1778)
						)
						(arc
							(start 0.2794 -0.1778)
							(mid 0.249642 -0.249642)
							(end 0.1778 -0.2794)
						)
					)
					(width 0)
					(fill yes)
				)
			)
		)
		(pad "2" smd custom
			(at 0 0.4445 180)
			(size 0.1397 0.1397)
			(layers "F.Cu" "F.Mask" "F.Paste")
			(net "ADM1276_GPIO2")
			(options
				(clearance outline)
				(anchor circle)
			)
			(primitives
				(gr_poly
					(pts
						(arc
							(start -0.1778 -0.2794)
							(mid -0.249642 -0.249642)
							(end -0.2794 -0.1778)
						)
						(arc
							(start -0.2794 0.1778)
							(mid -0.249642 0.249642)
							(end -0.1778 0.2794)
						)
						(arc
							(start 0.1778 0.2794)
							(mid 0.249642 0.249642)
							(end 0.2794 0.1778)
						)
						(arc
							(start 0.2794 -0.1778)
							(mid 0.249642 -0.249642)
							(end 0.1778 -0.2794)
						)
					)
					(width 0)
					(fill yes)
				)
			)
		)
	)
	(footprint ""
		(layer "F.Cu")
		(at 26.289 -151.3078)
		(property "Reference" "C5"
			(at 0 0 0)
			(layer "F.SilkS")
			(hide yes)
			(effects
				(font
					(size 1.27 1.27)
				)
			)
		)
		(property "Value" "SCD1U16V2KX-3GP"
			(at 1.1811 -2.7051 0)
			(unlocked yes)
			(layer "F.Fab")
			(hide yes)
			(effects
				(font
					(size 1.016 1.016)
					(thickness 0.1524)
				)
			)
		)
		(property "Device Type" "C402H22"
			(at 1.1811 -4.2291 0)
			(unlocked yes)
			(layer "F.Fab")
			(hide yes)
			(effects
				(font
					(size 1.016 1.016)
					(thickness 0.1524)
				)
			)
		)
		(duplicate_pad_numbers_are_jumpers no)
		(fp_rect
			(start -0.4318 0.9525)
			(end 0.4318 -0.9525)
			(stroke
				(width 0)
				(type default)
			)
			(fill no)
			(layer "F.CrtYd")
		)
		(fp_rect
			(start -0.4318 0.9525)
			(end 0.4318 -0.9525)
			(stroke
				(width 0)
				(type default)
			)
			(fill no)
			(layer "F.Fab")
		)
		(pad "1" smd custom
			(at 0 -0.4445)
			(size 0.1524 0.1524)
			(layers "F.Cu" "F.Mask" "F.Paste")
			(net "NCT7904_VREF")
			(options
				(clearance outline)
				(anchor circle)
			)
			(primitives
				(gr_poly
					(pts
						(arc
							(start 0.3048 -0.2032)
							(mid 0.275042 -0.275042)
							(end 0.2032 -0.3048)
						)
						(arc
							(start -0.2032 -0.3048)
							(mid -0.275042 -0.275042)
							(end -0.3048 -0.2032)
						)
						(arc
							(start -0.3048 0.2032)
							(mid -0.275042 0.275042)
							(end -0.2032 0.3048)
						)
						(arc
							(start 0.2032 0.3048)
							(mid 0.275042 0.275042)
							(end 0.3048 0.2032)
						)
					)
					(width 0)
					(fill yes)
				)
			)
		)
		(pad "2" smd custom
			(at 0 0.4445)
			(size 0.1524 0.1524)
			(layers "F.Cu" "F.Mask" "F.Paste")
			(net "GND")
			(options
				(clearance outline)
				(anchor circle)
			)
			(primitives
				(gr_poly
					(pts
						(arc
							(start 0.3048 -0.2032)
							(mid 0.275042 -0.275042)
							(end 0.2032 -0.3048)
						)
						(arc
							(start -0.2032 -0.3048)
							(mid -0.275042 -0.275042)
							(end -0.3048 -0.2032)
						)
						(arc
							(start -0.3048 0.2032)
							(mid -0.275042 0.275042)
							(end -0.2032 0.3048)
						)
						(arc
							(start 0.2032 0.3048)
							(mid 0.275042 0.275042)
							(end 0.3048 0.2032)
						)
					)
					(width 0)
					(fill yes)
				)
			)
		)
	)
	(footprint ""
		(layer "F.Cu")
		(at 38.6334 -254.381)
		(property "Reference" "R58"
			(at 0 0 0)
			(layer "F.SilkS")
			(hide yes)
			(effects
				(font
					(size 1.27 1.27)
				)
			)
		)
		(property "Value" "330R2J-3-GP"
			(at 0.064008 -3.993896 0)
			(unlocked yes)
			(layer "F.Fab")
			(hide yes)
			(effects
				(font
					(size 1.016 1.016)
					(thickness 0.1524)
				)
			)
		)
		(property "Device Type" "R402H16"
			(at 0.064008 -5.517896 0)
			(unlocked yes)
			(layer "F.Fab")
			(hide yes)
			(effects
				(font
					(size 1.016 1.016)
					(thickness 0.1524)
				)
			)
		)
		(duplicate_pad_numbers_are_jumpers no)
		(fp_line
			(start -0.508 -0.9398)
			(end -0.508 0.9398)
			(stroke
				(width 0.1524)
				(type default)
			)
			(layer "F.SilkS")
		)
		(fp_line
			(start 0.508 -0.9398)
			(end -0.508 -0.9398)
			(stroke
				(width 0.1524)
				(type default)
			)
			(layer "F.SilkS")
		)
		(fp_rect
			(start -0.508 0.9398)
			(end 0.508 -0.9398)
			(stroke
				(width 0)
				(type default)
			)
			(fill no)
			(layer "F.CrtYd")
		)
		(fp_rect
			(start -0.508 0.9398)
			(end 0.508 -0.9398)
			(stroke
				(width 0)
				(type default)
			)
			(fill no)
			(layer "F.Fab")
		)
		(pad "1" smd custom
			(at 0 -0.4445)
			(size 0.1397 0.1397)
			(layers "F.Cu" "F.Mask" "F.Paste")
			(net "P3V3")
			(options
				(clearance outline)
				(anchor circle)
			)
			(primitives
				(gr_poly
					(pts
						(arc
							(start -0.1778 -0.2794)
							(mid -0.249642 -0.249642)
							(end -0.2794 -0.1778)
						)
						(arc
							(start -0.2794 0.1778)
							(mid -0.249642 0.249642)
							(end -0.1778 0.2794)
						)
						(arc
							(start 0.1778 0.2794)
							(mid 0.249642 0.249642)
							(end 0.2794 0.1778)
						)
						(arc
							(start 0.2794 -0.1778)
							(mid 0.249642 -0.249642)
							(end 0.1778 -0.2794)
						)
					)
					(width 0)
					(fill yes)
				)
			)
		)
		(pad "2" smd custom
			(at 0 0.4445)
			(size 0.1397 0.1397)
			(layers "F.Cu" "F.Mask" "F.Paste")
			(net "LED_DR_LED6_RESERVE")
			(options
				(clearance outline)
				(anchor circle)
			)
			(primitives
				(gr_poly
					(pts
						(arc
							(start -0.1778 -0.2794)
							(mid -0.249642 -0.249642)
							(end -0.2794 -0.1778)
						)
						(arc
							(start -0.2794 0.1778)
							(mid -0.249642 0.249642)
							(end -0.1778 0.2794)
						)
						(arc
							(start 0.1778 0.2794)
							(mid 0.249642 0.249642)
							(end 0.2794 0.1778)
						)
						(arc
							(start 0.2794 -0.1778)
							(mid 0.249642 -0.249642)
							(end 0.1778 -0.2794)
						)
					)
					(width 0)
					(fill yes)
				)
			)
		)
	)
	(footprint ""
		(layer "F.Cu")
		(at 20.828 -179.1716 180)
		(property "Reference" "R87"
			(at 0 0 180)
			(layer "F.SilkS")
			(hide yes)
			(effects
				(font
					(size 1.27 1.27)
				)
			)
		)
		(property "Value" "27KR3F-GP"
			(at -0.0254 -2.5146 180)
			(unlocked yes)
			(layer "F.Fab")
			(hide yes)
			(effects
				(font
					(size 1.016 1.016)
					(thickness 0.1524)
				)
			)
		)
		(property "Device Type" "R603H22"
			(at -0.0254 -4.0386 180)
			(unlocked yes)
			(layer "F.Fab")
			(hide yes)
			(effects
				(font
					(size 1.016 1.016)
					(thickness 0.1524)
				)
			)
		)
		(duplicate_pad_numbers_are_jumpers no)
		(fp_line
			(start 0.2032 0)
			(end 0.4826 0)
			(stroke
				(width 0.2032)
				(type default)
			)
			(layer "F.SilkS")
		)
		(fp_line
			(start -0.4826 0)
			(end -0.2032 0)
			(stroke
				(width 0.2032)
				(type default)
			)
			(layer "F.SilkS")
		)
		(fp_rect
			(start -0.5842 1.3335)
			(end 0.5842 -1.3335)
			(stroke
				(width 0)
				(type default)
			)
			(fill no)
			(layer "F.CrtYd")
		)
		(fp_rect
			(start -0.5842 1.3335)
			(end 0.5842 -1.3335)
			(stroke
				(width 0)
				(type default)
			)
			(fill no)
			(layer "F.Fab")
		)
		(pad "1" smd custom
			(at 0 -0.762 180)
			(size 0.2159 0.2159)
			(layers "F.Cu" "F.Mask" "F.Paste")
			(net "FANIN_7")
			(options
				(clearance outline)
				(anchor circle)
			)
			(primitives
				(gr_poly
					(pts
						(arc
							(start -0.3302 -0.4318)
							(mid -0.402042 -0.402042)
							(end -0.4318 -0.3302)
						)
						(arc
							(start -0.4318 0.3302)
							(mid -0.402042 0.402042)
							(end -0.3302 0.4318)
						)
						(arc
							(start 0.3302 0.4318)
							(mid 0.402042 0.402042)
							(end 0.4318 0.3302)
						)
						(arc
							(start 0.4318 -0.3302)
							(mid 0.402042 -0.402042)
							(end 0.3302 -0.4318)
						)
					)
					(width 0)
					(fill yes)
				)
			)
		)
		(pad "2" smd custom
			(at 0 0.762 180)
			(size 0.2159 0.2159)
			(layers "F.Cu" "F.Mask" "F.Paste")
			(net "FAN_TACH7")
			(options
				(clearance outline)
				(anchor circle)
			)
			(primitives
				(gr_poly
					(pts
						(arc
							(start -0.3302 -0.4318)
							(mid -0.402042 -0.402042)
							(end -0.4318 -0.3302)
						)
						(arc
							(start -0.4318 0.3302)
							(mid -0.402042 0.402042)
							(end -0.3302 0.4318)
						)
						(arc
							(start 0.3302 0.4318)
							(mid 0.402042 0.402042)
							(end 0.4318 0.3302)
						)
						(arc
							(start 0.4318 -0.3302)
							(mid 0.402042 -0.402042)
							(end 0.3302 -0.4318)
						)
					)
					(width 0)
					(fill yes)
				)
			)
		)
	)
	(footprint ""
		(layer "F.Cu")
		(at 26.0604 -224.3074)
		(property "Reference" "R141"
			(at 0 0 0)
			(layer "F.SilkS")
			(hide yes)
			(effects
				(font
					(size 1.27 1.27)
				)
			)
		)
		(property "Value" "0R2J-2-GP"
			(at 0.064008 -3.993896 0)
			(unlocked yes)
			(layer "F.Fab")
			(hide yes)
			(effects
				(font
					(size 1.016 1.016)
					(thickness 0.1524)
				)
			)
		)
		(property "Device Type" "R402H16"
			(at 0.064008 -5.517896 0)
			(unlocked yes)
			(layer "F.Fab")
			(hide yes)
			(effects
				(font
					(size 1.016 1.016)
					(thickness 0.1524)
				)
			)
		)
		(duplicate_pad_numbers_are_jumpers no)
		(fp_line
			(start -0.508 -0.9398)
			(end -0.508 0.9398)
			(stroke
				(width 0.1524)
				(type default)
			)
			(layer "F.SilkS")
		)
		(fp_line
			(start 0.508 -0.9398)
			(end -0.508 -0.9398)
			(stroke
				(width 0.1524)
				(type default)
			)
			(layer "F.SilkS")
		)
		(fp_rect
			(start -0.508 0.9398)
			(end 0.508 -0.9398)
			(stroke
				(width 0)
				(type default)
			)
			(fill no)
			(layer "F.CrtYd")
		)
		(fp_rect
			(start -0.508 0.9398)
			(end 0.508 -0.9398)
			(stroke
				(width 0)
				(type default)
			)
			(fill no)
			(layer "F.Fab")
		)
		(pad "1" smd custom
			(at 0 -0.4445)
			(size 0.1397 0.1397)
			(layers "F.Cu" "F.Mask" "F.Paste")
			(net "PWM_OUT_FAN1_NET")
			(options
				(clearance outline)
				(anchor circle)
			)
			(primitives
				(gr_poly
					(pts
						(arc
							(start -0.1778 -0.2794)
							(mid -0.249642 -0.249642)
							(end -0.2794 -0.1778)
						)
						(arc
							(start -0.2794 0.1778)
							(mid -0.249642 0.249642)
							(end -0.1778 0.2794)
						)
						(arc
							(start 0.1778 0.2794)
							(mid 0.249642 0.249642)
							(end 0.2794 0.1778)
						)
						(arc
							(start 0.2794 -0.1778)
							(mid 0.249642 -0.249642)
							(end 0.1778 -0.2794)
						)
					)
					(width 0)
					(fill yes)
				)
			)
		)
		(pad "2" smd custom
			(at 0 0.4445)
			(size 0.1397 0.1397)
			(layers "F.Cu" "F.Mask" "F.Paste")
			(net "PWM_OUT_FAN1")
			(options
				(clearance outline)
				(anchor circle)
			)
			(primitives
				(gr_poly
					(pts
						(arc
							(start -0.1778 -0.2794)
							(mid -0.249642 -0.249642)
							(end -0.2794 -0.1778)
						)
						(arc
							(start -0.2794 0.1778)
							(mid -0.249642 0.249642)
							(end -0.1778 0.2794)
						)
						(arc
							(start 0.1778 0.2794)
							(mid 0.249642 0.249642)
							(end 0.2794 0.1778)
						)
						(arc
							(start 0.2794 -0.1778)
							(mid 0.249642 -0.249642)
							(end 0.1778 -0.2794)
						)
					)
					(width 0)
					(fill yes)
				)
			)
		)
	)
	(footprint ""
		(layer "F.Cu")
		(at 14.8844 -71.12 -90)
		(property "Reference" "R167"
			(at 0 0 270)
			(layer "F.SilkS")
			(hide yes)
			(effects
				(font
					(size 1.27 1.27)
				)
			)
		)
		(property "Value" "4K7R2F-GP"
			(at 0.064008 -3.993896 270)
			(unlocked yes)
			(layer "F.Fab")
			(hide yes)
			(effects
				(font
					(size 1.016 1.016)
					(thickness 0.1524)
				)
			)
		)
		(property "Device Type" "R402H16"
			(at 0.064008 -5.517896 270)
			(unlocked yes)
			(layer "F.Fab")
			(hide yes)
			(effects
				(font
					(size 1.016 1.016)
					(thickness 0.1524)
				)
			)
		)
		(duplicate_pad_numbers_are_jumpers no)
		(fp_line
			(start -0.508 -0.9398)
			(end -0.508 0.9398)
			(stroke
				(width 0.1524)
				(type default)
			)
			(layer "F.SilkS")
		)
		(fp_line
			(start 0.508 -0.9398)
			(end -0.508 -0.9398)
			(stroke
				(width 0.1524)
				(type default)
			)
			(layer "F.SilkS")
		)
		(fp_rect
			(start -0.508 0.9398)
			(end 0.508 -0.9398)
			(stroke
				(width 0)
				(type default)
			)
			(fill no)
			(layer "F.CrtYd")
		)
		(fp_rect
			(start -0.508 0.9398)
			(end 0.508 -0.9398)
			(stroke
				(width 0)
				(type default)
			)
			(fill no)
			(layer "F.Fab")
		)
		(pad "1" smd custom
			(at 0 -0.4445 270)
			(size 0.1397 0.1397)
			(layers "F.Cu" "F.Mask" "F.Paste")
			(net "P3V3")
			(options
				(clearance outline)
				(anchor circle)
			)
			(primitives
				(gr_poly
					(pts
						(arc
							(start -0.1778 -0.2794)
							(mid -0.249642 -0.249642)
							(end -0.2794 -0.1778)
						)
						(arc
							(start -0.2794 0.1778)
							(mid -0.249642 0.249642)
							(end -0.1778 0.2794)
						)
						(arc
							(start 0.1778 0.2794)
							(mid 0.249642 0.249642)
							(end 0.2794 0.1778)
						)
						(arc
							(start 0.2794 -0.1778)
							(mid 0.249642 -0.249642)
							(end 0.1778 -0.2794)
						)
					)
					(width 0)
					(fill yes)
				)
			)
		)
		(pad "2" smd custom
			(at 0 0.4445 270)
			(size 0.1397 0.1397)
			(layers "F.Cu" "F.Mask" "F.Paste")
			(net "PWM_BUFFER_IN_FAN1_FAN2")
			(options
				(clearance outline)
				(anchor circle)
			)
			(primitives
				(gr_poly
					(pts
						(arc
							(start -0.1778 -0.2794)
							(mid -0.249642 -0.249642)
							(end -0.2794 -0.1778)
						)
						(arc
							(start -0.2794 0.1778)
							(mid -0.249642 0.249642)
							(end -0.1778 0.2794)
						)
						(arc
							(start 0.1778 0.2794)
							(mid 0.249642 0.249642)
							(end 0.2794 0.1778)
						)
						(arc
							(start 0.2794 -0.1778)
							(mid 0.249642 -0.249642)
							(end 0.1778 -0.2794)
						)
					)
					(width 0)
					(fill yes)
				)
			)
		)
	)
	(footprint ""
		(layer "F.Cu")
		(at 31.877 -22.479 90)
		(property "Reference" "TC13"
			(at 0 0 90)
			(layer "F.SilkS")
			(hide yes)
			(effects
				(font
					(size 1.27 1.27)
				)
			)
		)
		(property "Value" "ST15U25VDM-1-GP"
			(at 0 -9.6012 90)
			(unlocked yes)
			(layer "F.Fab")
			(hide yes)
			(effects
				(font
					(size 1.016 1.016)
					(thickness 0.1524)
				)
			)
		)
		(property "Device Type" "CT7343H79"
			(at 0 -11.1252 90)
			(unlocked yes)
			(layer "F.Fab")
			(hide yes)
			(effects
				(font
					(size 1.016 1.016)
					(thickness 0.1524)
				)
			)
		)
		(duplicate_pad_numbers_are_jumpers no)
		(fp_line
			(start 2.286 -4.8768)
			(end -2.286 -4.8768)
			(stroke
				(width 0.1524)
				(type default)
			)
			(layer "F.SilkS")
		)
		(fp_line
			(start -2.286 -4.8768)
			(end -2.286 -2.032)
			(stroke
				(width 0.1524)
				(type default)
			)
			(layer "F.SilkS")
		)
		(fp_line
			(start 2.1082 -4.699)
			(end -2.1082 -4.699)
			(stroke
				(width 0.508)
				(type default)
			)
			(layer "F.SilkS")
		)
		(fp_line
			(start 2.286 -2.032)
			(end 2.286 -4.8768)
			(stroke
				(width 0.1524)
				(type default)
			)
			(layer "F.SilkS")
		)
		(fp_line
			(start 2.286 2.032)
			(end 2.286 4.8768)
			(stroke
				(width 0.1524)
				(type default)
			)
			(layer "F.SilkS")
		)
		(fp_line
			(start 2.286 4.8768)
			(end -2.286 4.8768)
			(stroke
				(width 0.1524)
				(type default)
			)
			(layer "F.SilkS")
		)
		(fp_line
			(start -2.286 4.8768)
			(end -2.286 2.032)
			(stroke
				(width 0.1524)
				(type default)
			)
			(layer "F.SilkS")
		)
		(fp_rect
			(start -2.1463 3.6449)
			(end 2.1463 -3.6449)
			(stroke
				(width 0)
				(type default)
			)
			(fill no)
			(layer "F.CrtYd")
		)
		(fp_poly
			(pts
				(xy -2.54 4.953) (xy -2.54 4.2926) (xy -3.81 4.2926) (xy -3.81 -4.2926) (xy -2.54 -4.2926) (xy -2.54 -4.953)
				(xy 2.54 -4.953) (xy 2.54 -4.2926) (xy 3.81 -4.2926) (xy 3.81 -1.6256) (xy 2.1463 -1.6256) (xy 2.1463 -3.6449)
				(xy -2.1463 -3.6449) (xy -2.1463 3.6449) (xy 2.1463 3.6449) (xy 2.1463 -1.6129) (xy 3.81 -1.6129)
				(xy 3.81 4.2926) (xy 2.54 4.2926) (xy 2.54 4.953)
			)
			(stroke
				(width 0)
				(type default)
			)
			(fill no)
			(layer "F.CrtYd")
		)
		(fp_rect
			(start 2.54 4.2926)
			(end 3.81 -4.2926)
			(stroke
				(width 0)
				(type default)
			)
			(fill no)
			(layer "F.Fab")
		)
		(fp_rect
			(start -3.81 4.2926)
			(end -2.54 -4.2926)
			(stroke
				(width 0)
				(type default)
			)
			(fill no)
			(layer "F.Fab")
		)
		(fp_rect
			(start -2.54 4.953)
			(end 2.54 -4.953)
			(stroke
				(width 0)
				(type default)
			)
			(fill no)
			(layer "F.Fab")
		)
		(pad "1" smd rect
			(at 0 -3.1496 90)
			(size 2.413 2.286)
			(layers "F.Cu" "F.Mask" "F.Paste")
			(net "P12V")
		)
		(pad "2" smd rect
			(at 0 3.1496 90)
			(size 2.413 2.286)
			(layers "F.Cu" "F.Mask" "F.Paste")
			(net "GND")
		)
		(zone
			(layer "F.Cu")
			(hatch none 0.5)
			(connect_pads
				(clearance 0)
			)
			(min_thickness 0.25)
			(keepout
				(tracks allowed)
				(vias not_allowed)
				(pads allowed)
				(copperpour not_allowed)
				(footprints allowed)
			)
			(placement
				(enabled no)
				(sheetname "")
			)
			(fill
				(thermal_gap 0.5)
				(thermal_bridge_width 0.5)
				(island_removal_mode 0)
			)
			(polygon
				(pts
					(xy 30.1879 -23.9903) (xy 27.2796 -23.9903) (xy 27.2796 -20.9677) (xy 30.1752 -20.9677) (xy 30.5054 -20.9677)
					(xy 30.5054 -23.9903)
				)
			)
		)
		(zone
			(layer "F.Cu")
			(hatch none 0.5)
			(connect_pads
				(clearance 0)
			)
			(min_thickness 0.25)
			(keepout
				(tracks allowed)
				(vias not_allowed)
				(pads allowed)
				(copperpour not_allowed)
				(footprints allowed)
			)
			(placement
				(enabled no)
				(sheetname "")
			)
			(fill
				(thermal_gap 0.5)
				(thermal_bridge_width 0.5)
				(island_removal_mode 0)
			)
			(polygon
				(pts
					(xy 36.4744 -20.9677) (xy 36.4744 -23.9903) (xy 33.5788 -23.9903) (xy 33.2486 -23.9903) (xy 33.2486 -20.9677)
					(xy 33.5788 -20.9677)
				)
			)
		)
	)
)
